FILE_TYPE = MULTI_PHYS_TABLE;

PART 'GND_HOLE'

{========================================================================================}
:PACK_TYPE | MATERIAL | PART_NUMBER             = STANDARD | LIFECYCLE | PART_NUMBER             | JEDEC_TYPE                               | CLASS | DESCRIPTION                                       | COMPONENT_TYPE | LEAD_LENGTH | DFM_EXCLUSION ;
{========================================================================================}
 'TH'      | 'EMPTY'  | 'QUANTA_N_A'(!)         = ''       | ''        | 'QUANTA_N_A'            |'GND_C10D4-3B10'| 'IO'  | 'SPOKE MOUNTING HOLE 169'                         | ''             | ''          | ''           
 'TH'      | 'EMPTY'  | 'TMP-Q_S08_SAM_0621_1'(!) = ''       | ''        | 'TMP-Q_S08_SAM_0621_1'  |'GND_C8D3-5B8'| 'IO'  | 'GNDHOLE_C8D3-5B8'                                | ''             | ''          | ''           
 'TH'      | 'EMPTY'  | 'GND_HOLE86'(!)         = ''       | ''        | 'GND_HOLE86'            |'GND_C9D4-3B9'| 'IO'  | 'GND_C9D4-3B9'                                    | ''             | ''          | ''           
 'TH'      | 'EMPTY'  | 'TMP-QGND_HOLE242'(!)   = ''       | ''        | 'TMP-QGND_HOLE242'      |'GND_C7-77D5-42B7-77'| 'IO'  | 'GNDHOLE_C7-77D5-42B7-77'                         | ''             | ''          | ''           
 'TH'      | 'EMPTY'  | 'TMP-QGND_HOLE55'(!)    = ''       | ''        | 'TMP-QGND_HOLE55'       |'GND_C8D4-5B8'| 'IO'  | 'GNDHOLE_8PIN_C8D4-5B8'                           | ''             | ''          | ''           
 'TH'      | 'EMPTY'  | 'TMP-C_LU2_MATT_0430_1'(!) = ''       | ''        | 'TMP-C_LU2_MATT_0430_1' |'GND_C7-3D3-56B7-3_OSP'| 'IO'  | 'GND_C7-3D3-56B7-3_OSP'                           | ''             | ''          | ''           
 'TH'      | 'EMPTY'  | 'TMP-C_LU2_MATT_0430_2'(!) = ''       | ''        | 'TMP-C_LU2_MATT_0430_2' |'GND_C7-3D4B7-3_OSP'| 'IO'  | 'GND_C7-3D4B7-3_OSP'                              | ''             | ''          | ''           
 'TH'      | 'EMPTY'  | 'TMP-QGND_HOLE12'(!)    = ''       | ''        | 'TMP-QGND_HOLE12'       |'GND_C8D4B8'| 'IO'  | 'GND_C8D4B8'                                      | ''             | ''          | ''           
 'TH'      | 'EMPTY'  | 'TMP-QGND_HOLE278'(!)   = ''       | ''        | 'TMP-QGND_HOLE278'      |'GND_C10D4-5B10'| 'IO'  | 'GND_C10D4-5B10'                                  | ''             | ''          | ''           
 'TH'      | 'EMPTY'  | 'TMP-QGND_HOLE69'(!)    = ''       | ''        | 'TMP-QGND_HOLE69'       |'GND_C10D4-5'| 'IO'  | 'GND_C10D4-5'                                     | ''             | ''          | ''           
 'TH'      | 'EMPTY'  | 'TMP-QGND_HOLE286'(!)   = ''       | ''        | 'TMP-QGND_HOLE286'      |'GND_C7-3D4-5B7-3_OSP'| 'IO'  | 'GND_C7-3D4-5B7-3_OSP'                            | ''             | ''          | ''           
 'TH'      | 'EMPTY'  | 'TMP-QGND_HOLE287'(!)   = ''       | ''        | 'TMP-QGND_HOLE287'      |'GND_C7-3D3-5B7-3_OSP'| 'IO'  | 'GND_C7-3D3-5B7-3_OSP'                            | ''             | ''          | ''           
 'TH'      | 'EMPTY'  | 'TMP-QGND_HOLE81'(!)    = ''       | ''        | 'TMP-QGND_HOLE81'       |'GND_C9D4'| 'IO'  | 'GND_C9D4'                                        | ''             | ''          | ''           
 'TH'      | 'EMPTY'  | 'TMP-QGND_HOLE289'(!)   = ''       | ''        | 'TMP-QGND_HOLE289'      |'GND_C10-2D3-7B10-2_OSP'| 'IO'  | 'GND_C10-2D3-7B10-2_OSP'                          | ''             | ''          | ''           
 'TH_SEL'  | 'EMPTY'  | 'GND_HOLE194'(!)        = ''       | ''        | 'GND_HOLE194'           |'G_GND_C10-16D3-96'| 'IO'  | 'GND_C10-16D3-96'                                 | ''             | ''          | ''           
 'TH'      | 'EMPTY'  | 'GND_HOLE288'(!)        = ''       | ''        | 'GND_HOLE288'           |'GND_C10D5-7B10'| 'IO'  | 'GND_C10D5-7B10'                                  | ''             | ''          | ''           
 'TH'      | 'EMPTY'  | 'GND_HOLE46'(!)         = ''       | ''        | 'GND_HOLE46'            |'GND_C10D4B10'| 'IO'  | 'GNDHOLE_8PIN_C10D4B10'                           | ''             | ''          | ''           
 'TH'      | 'EMPTY'  | 'GND_HOLE307'(!)        = ''       | ''        | 'GND_HOLE307'           |'GND_C11D6-4B11'| 'IO'  | 'GND_C11D6-4B11'                                  | ''             | ''          | ''           
 'TH'      | 'EMPTY'  | 'GND_HOLE306'(!)        = ''       | ''        | 'GND_HOLE306'           |'GND_C11D6-2B11'| 'IO'  | 'GND_C11D6-2B11'                                  | ''             | ''          | ''           
 'TH'      | 'EMPTY'  | 'GND_HOLE311'(!)        = ''       | ''        | 'GND_HOLE311'           |'GND_C10D4-8B10'| 'IO'  | 'GND_C10D4-8B10'                                  | ''             | ''          | ''           
 'TH'      | 'EMPTY'  | 'GND_HOLE312'(!)        = ''       | ''        | 'GND_HOLE312'           |'GND_C10D3-6B10'| 'IO'  | 'GND_C10D3-6B10'                                  | ''             | ''          | ''           
 'TH'      | 'EMPTY'  | 'GND_HOLE47'(!)         = ''       | ''        | 'GND_HOLE47'            |'GND_C9D4-5B9'| 'IO'  | 'GND_C9D4-5B9'                                    | ''             | ''          | ''           
 'TH'      | 'EMPTY'  | 'GND_HOLE231'(!)        = ''       | ''        | 'GND_HOLE231'           |'GND_C8D4-3B8'| 'IO'  | 'GND_C8D4-3B8'                                    | ''             | ''          | ''           
 'TH'      | 'EMPTY'  | 'GND_HOLE277'(!)        = ''       | ''        | 'GND_HOLE277'           |'GND_R10X11D4B10X11'| 'IO'  | 'GND_R10X11D4B10X11'                              | ''             | ''          | ''           
 'TH'      | 'EMPTY'  | 'GND_HOLE315'(!)        = ''       | ''        | 'GND_HOLE315'           |'GND_C8-5D5-6B8-5'| 'IO'  | 'GND_C8-5D5-6B8-5'                                | ''             | ''          | ''           
 'TH'      | 'EMPTY'  | 'GND_HOLE318'(!)        = ''       | ''        | 'GND_HOLE318'           |'GND_C10D4-5B10_CUTB_OSP-T'| 'IO'  | 'GND_C10D4-5B10_CUTB_OSP-T'                       | ''             | ''          | ''           
 'TH'      | 'EMPTY'  | 'GND_HOLE320'(!)        = ''       | ''        | 'GND_HOLE320'           |'GND_C8-6D5-6B12_OB3-5XC6B'| 'IO'  | 'GND_C8-6D5-6B12_OB3-5XC6B'                       | ''             | ''          | ''           
 'TH'      | 'EMPTY'  | 'GND_HOLE259'(!)        = ''       | ''        | 'GND_HOLE259'           |'GND_C10D4-3B10_OSP-T'| 'IO'  | 'GND_C10D4-3B10_OSP-T'                            | ''             | ''          | ''           
 'TH'      | 'EMPTY'  | 'GND_HOLE29'(!)         = ''       | ''        | 'GND_HOLE29'            |'GND_C9D5B9'| 'IO'  | 'GND_C9D5B9'                                      | ''             | ''          | ''           
 'TH'      | 'EMPTY'  | 'GND_HOLE140'(!)        = ''       | ''        | 'GND_HOLE140'           |'GND_C10D5-5B10'| 'IO'  | 'GNDHOLE_8PIN_C10D5-5B10'                         | ''             | ''          | ''           
 'TH'      | 'EMPTY'  | 'GND_HOLE192'(!)        = ''       | ''        | 'GND_HOLE192'           |'GND_C10D3-8B10'| 'IO'  | 'GNDHOLE_C10D3-8B10'                              | ''             | ''          | ''           
 'TH'      | 'EMPTY'  | 'GND_HOLE149'(!)        = ''       | ''        | 'GND_HOLE149'           |'GND_C10D4B10'| 'IO'  | 'GNDHOLE_8PIN_C10D4B10'                           | ''             | ''          | ''           
 'TH'      | 'EMPTY'  | 'GND_HOLE325'(!)        = ''       | ''        | 'GND_HOLE325'           |'GND_R10X13-6D4B10_Y-1-8T_CUTA'| 'IO'  | 'GNDHOLE_8PIN_R10X13-6D4B10_Y-1-8T_CUTA'          | ''             | ''          | ''           
 'TH'      | 'EMPTY'  | 'GND_HOLE13'(!)         = ''       | ''        | 'GND_HOLE13'            |'GND_C8D4'| 'IO'  | 'GNDHOLE_8PIN_C8D4'                               | ''             | ''          | ''           
 'TH'      | 'EMPTY'  | 'GND_HOLE333'(!)        = ''       | ''        | 'GND_HOLE333'           |'GND_C11-6D5-6B11-6_OB16XC5-8B'| 'IO'  | 'GND_C11-6D5-6B11-6_OB16XC5-8B'                   | ''             | ''          | ''           
 'TH'      | 'EMPTY'  | 'GND_HOLE336'(!)        = ''       | ''        | 'GND_HOLE336'           |'GND_C10D3-7B10_OB5-5XC5B'| 'IO'  | 'GND_C10D3-7B10_OB5-5XC5B'                        | ''             | ''          | ''           
 'TH'      | 'EMPTY'  | 'GND_HOLE134'(!)        = ''       | ''        | 'GND_HOLE134'           |'GND_C13D5-6B13'| 'IO'  | 'GND_C13D5-6B13'                                  | ''             | ''          | ''           
 'TH'      | 'EMPTY'  | 'GND_HOLE112'(!)        = ''       | ''        | 'GND_HOLE112'           |'GND_C9D5-3B9'| 'IO'  | 'GND_C9D5-3B9'                                    | ''             | ''          | ''           
 'TH'      | 'EMPTY'  | 'GND_HOLE28'(!)         = ''       | ''        | 'GND_HOLE28'            |'GND_C9D4B9'| 'IO'  | 'GND_C9D4B9'                                      | ''             | ''          | ''           
 'TH'      | 'EMPTY'  | 'GND_HOLE344'(!)        = ''       | ''        | 'GND_HOLE344'           |'GND_C10D3-5B10'| 'IO'  | 'GND_C10D3-5B10'                                  | ''             | ''          | ''           
 'TH'      | 'EMPTY'  | 'GND_HOLE326'(!)        = ''       | ''        | 'GND_HOLE326'           |'GND_C9D4B8_OB6XC4BN'| 'IO'  | 'GND_C9D4B8_OB6XC4BN'                             | ''             | ''          | ''           
 'TH'      | 'EMPTY'  | 'GND_HOLE219'(!)        = ''       | ''        | 'GND_HOLE219'           |'GND_C9D5-41B9'| 'IO'  | 'GNDHOLE_8PIN_C9D5-41B9'                          | ''             | ''          | ''           
 'TH'      | 'EMPTY'  | 'GND_HOLE349'(!)        = ''       | ''        | 'GND_HOLE349'           |'GND_C9D4B9_OB3-5X4-5B'| 'IO'  | 'GND_C9D4B9_OB3-5X4-5B'                           | ''             | ''          | ''           
 'TH'      | 'EMPTY'  | 'GND_HOLE104'(!)        = ''       | ''        | 'GND_HOLE104'           |'GND_C9D3-2B9'| 'IO'  | 'GND_C9D3-2B9'                                    | ''             | ''          | ''           
 'TH'      | 'EMPTY'  | 'GND_HOLE21'(!)         = ''       | ''        | 'GND_HOLE21'            |'GND_C8D3-6B8'| 'IO'  | 'GND_C8D3-6B8'                                    | ''             | ''          | ''           
 'TH'      | 'EMPTY'  | 'GND_HOLE26'(!)         = ''       | ''        | 'GND_HOLE26'            |'GND_C10D3-2B10'| 'IO'  | 'GND_C10D3-2B10'                                  | ''             | ''          | ''           
 'TH'      | 'EMPTY'  | 'GND_HOLE352'(!)        = ''       | ''        | 'GND_HOLE352'           |'GND_C10D3-9B10'| 'IO'  | 'GND_C10D3-9B10'                                  | ''             | ''          | ''           
 'TH'      | 'EMPTY'  | 'GND_HOLE266'(!)        = ''       | ''        | 'GND_HOLE266'           |'GND_R9X9-5D3-6B9X9-5'| 'IO'  | 'GND_R9X9-5D3-6B9X9-5'                            | ''             | ''          | ''           
 'TH'      | 'EMPTY'  | 'GND_HOLE160'(!)        = ''       | ''        | 'GND_HOLE160'           |'GND_C7-5D4-3'| 'IO'  | 'GND_C7-5D4-3'                                    | ''             | ''          | ''           
 'TH'      | 'EMPTY'  | 'GND_HOLE319'(!)        = ''       | ''        | 'GND_HOLE319'           |'GND_C10D4B10_OB5XC5B'| 'IO'  | 'GND_C10D4B10_OB5XC5B'                            | ''             | ''          | ''           
 'TH'      | 'EMPTY'  | 'GND_HOLE264'(!)        = ''       | ''        | 'GND_HOLE264'           |'GND_C8D4B10_OB7XC5B'| 'IO'  | 'GND_C8D4B10_OB7XC5B'                             | ''             | ''          | ''           
 'TH'      | 'EMPTY'  | 'GND_HOLE16'(!)         = ''       | ''        | 'GND_HOLE16'            |'GND_C7D4B7'| 'IO'  | 'GND_C7D4B7'                                      | ''             | ''          | ''           
 'TH'      | 'EMPTY'  | 'GND_HOLE364'(!)        = ''       | ''        | 'GND_HOLE364'           |'GND_C8D4B9_OB3-5XC4-5B'| 'IO'  | 'GND_C8D4B9_OB3-5XC4-5B'                          | ''             | ''          | ''           
 'TH'      | 'EMPTY'  | 'GND_HOLE370'(!)        = ''       | ''        | 'GND_HOLE370'           |'GND_C10D4B10_OB10XC5B'| 'IO'  | 'GND_C10D4B10_OB10XC5B'                           | ''             | ''          | ''           
 'TH'      | 'EMPTY'  | 'GND_HOLE371'(!)        = ''       | ''        | 'GND_HOLE371'           |'GND_C10D3-6B10_OB3-5XC5B'| 'IO'  | 'GND_C10D3-6B10_OB3-5XC5B'                        | ''             | ''          | ''           
 'TH'      | 'EMPTY'  | 'GND_HOLE372'(!)        = ''       | ''        | 'GND_HOLE372'           |'GND_C10D3-1B10_OB3-5XC5B'| 'IO'  | 'GND_C10D3-1B10_OB3-5XC5B'                        | ''             | ''          | ''           
 'TH'      | 'EMPTY'  | 'GND_HOLE167'(!)        = ''       | ''        | 'GND_HOLE167'           |'GND_C10-16D3-5B10-16'| 'IO'  | 'GND_C10-16D3-5B10-16'                            | ''             | ''          | ''           
 'TH'      | 'EMPTY'  | 'GND_HOLE375'(!)        = ''       | ''        | 'GND_HOLE375'           |'GND_C10D5-6B10_OB3-5XC5T'| 'IO'  | 'GND_C10D5-6B10_OB3-5XC5T'                        | ''             | ''          | ''           
 'TH'      | 'EMPTY'  | 'GND_HOLE376'(!)        = ''       | ''        | 'GND_HOLE376'           |'GND_C10D5-6B10_OB3-5XC5B'| 'IO'  | 'GND_C10D5-6B10_OB3-5XC5B'                        | ''             | ''          | ''           
 'TH'      | 'EMPTY'  | 'GND_HOLE379'(!)        = ''       | ''        | 'GND_HOLE379'           |'GND_C10OB4-8X5-4B10'| 'IO'  | 'GND_C10OB4-8X5-4B10'                             | ''             | ''          | ''           
 'TH'      | 'EMPTY'  | 'GND_HOLE383'(!)        = ''       | ''        | 'GND_HOLE383'           |'GND_C10D4B8_OB3-5XC4B'| 'IO'  | 'GND_C10D4B8_OB3-5XC4B'                           | ''             | ''          | ''           
 'TH'      | 'EMPTY'  | 'GND_HOLE384'(!)        = ''       | ''        | 'GND_HOLE384'           |'GND_R15X16D4-8B10_IX0-5'| 'IO'  | 'GND_R15X16D4-8B10_IX0-5'                         | ''             | ''          | ''           
 'TH'      | 'EMPTY'  | 'GND_HOLE385'(!)        = ''       | ''        | 'GND_HOLE385'           |'GND_C10D3-6B9_OB5XC4-5B'| 'IO'  | 'GND_C10D3-6B9_OB5XC4-5B'                         | ''             | ''          | ''           
 'TH'      | 'EMPTY'  | 'GND_HOLE386'(!)        = ''       | ''        | 'GND_HOLE386'           |'GND_C10D3-6B10_OB6XC5B'| 'IO'  | 'GND_C10D3-6B10_OB6XC5B'                          | ''             | ''          | ''           
 'TH'      | 'EMPTY'  | 'GND_HOLE389'(!)        = ''       | ''        | 'GND_HOLE389'           |'GND_C10D3-1B10'| 'IO'  | 'GND_C10D3-1B10'                                  | ''             | ''          | ''           
 'TH'      | 'EMPTY'  | 'GND_HOLE243'(!)        = ''       | ''        | 'GND_HOLE243'           |'GND_C8D3-1B8'| 'IO'  | 'GND_C8D3-1B8'                                    | ''             | ''          | ''           
 'TH'      | 'EMPTY'  | 'GND_HOLE391'(!)        = ''       | ''        | 'GND_HOLE391'           |'GND_C9D3-6B9_OB9XC4-5B'| 'IO'  | 'GND_C9D3-6B9_OB9XC4-5B'                          | ''             | ''          | ''           
 'TH'      | 'EMPTY'  | 'GND_HOLE392'(!)        = ''       | ''        | 'GND_HOLE392'           |'GND_C9D3-6B9_OB5XC4-5B'| 'IO'  | 'GND_C9D3-6B9_OB5XC4-5B'                          | ''             | ''          | ''           
 'TH'      | 'EMPTY'  | 'GND_HOLE393'(!)        = ''       | ''        | 'GND_HOLE393'           |'GND_C10D3-2B10_OB3-5XC5B'| 'IO'  | 'GND_C10D3-2B10_OB3-5XC5B'                        | ''             | ''          | ''           
 'TH'      | 'EMPTY'  | 'GND_HOLE394'(!)        = ''       | ''        | 'GND_HOLE394'           |'GND_C10D3-2B10_OB3-5XC5T_RB'| 'IO'  | 'GND_C10D3-2B10_OB3-5XC5T_RB'                     | ''             | ''          | ''           
 'TH'      | 'EMPTY'  | 'GND_HOLE398'(!)        = ''       | ''        | 'GND_HOLE398'           |'GND_C10-5OBD5-5X6-5B10-5_OB4-5XC5-25B'| 'IO'  | 'GND_C10-5OBD5-5X6-5B10-5_OB4-5XC5-25B'           | ''             | ''          | ''           
 'TH'      | 'EMPTY'  | 'GND_HOLE399'(!)        = ''       | ''        | 'GND_HOLE399'           |'GND_C10D7-8X5-8B10_OB6XC5B'| 'IO'  | 'GND_C10D7-8X5-8B10_OB6XC5B'                      | ''             | ''          | ''           
 'TH'      | 'EMPTY'  | 'GND_HOLE407'(!)        = ''       | ''        | 'GND_HOLE407'           |'GND_C10D4B10_OB10XC5T_RB'| 'IO'  | 'GND_C10D4B10_OB10XC5T_RB'                        | ''             | ''          | ''           
 'TH'      | 'EMPTY'  | 'GND_HOLE423'(!)        = ''       | ''        | 'GND_HOLE423'           |'GND_C10D3-5B10_OB6XC5B'| 'IO'  | 'GND_C10D3-5B10_OB6XC5B'                          | ''             | ''          | ''           
 'TH'      | 'EMPTY'  | 'GND_HOLE45'(!)         = ''       | ''        | 'GND_HOLE45'            |'GND_C10D5B10'| 'IO'  | 'GND_C10D5B10'                                    | ''             | ''          | ''           
 'TH'      | 'EMPTY'  | 'GND_HOLE428'(!)        = ''       | ''        | 'GND_HOLE428'           |'GND_C10-16D3-96B10-16_OB7-62XC5-08B'| 'IO'  | 'GND_C10-16D3-96B10-16_OB7-62XC5-08B'             | ''             | ''          | ''           
 'TH'      | 'EMPTY'  | 'SP_GND_HOLE428'(!)     = ''       | ''        | 'SP_GND_HOLE428'        |'G_GND_C10-16D3-96B10-16_OB7-62XC5-08B'| 'IO'  | 'GND_C10-16D3-96B10-16_OB7-62XC5-08B_FOR SEL'     | ''             | ''          | ''           
 'TH'      | 'EMPTY'  | 'GND_HOLE430'(!)        = ''       | ''        | 'GND_HOLE430'           |'GND_C10D3-5B10_OB28XC5B'| 'IO'  | 'GND_C10D3-5B10_OB28XC5B'                         | ''             | ''          | ''           
 'TH'      | 'EMPTY'  | 'GND_HOLE433'(!)        = ''       | ''        | 'GND_HOLE433'           |'GND_C10-16D3-66B10-16_OB7-62XC5-08B'| 'IO'  | 'GND_C10-16D3-66B10-16_OB7-62XC5-08B'             | ''             | ''          | ''           
 'TH'      | 'EMPTY'  | 'SP_GND_HOLE433'(!)     = ''       | ''        | 'GND_HOLE433'           |'G_GND_C10-16D3-66B10-16_OB7-62XC5-08B'| 'IO'  | 'GND_C10-16D3-66B10-16_OB7-62XC5-08B_FOR SEL'     | ''             | ''          | ''           
 'TH'      | 'EMPTY'  | 'SP_GND_HOLE46'(!)      = ''       | ''        | 'GND_HOLE46'            |'G_GND_C10D4B10'| 'IO'  | 'GNDHOLE_8PIN_C10D4B10_FOR SEL'                   | ''             | ''          | ''           
 'TH'      | 'EMPTY'  | 'GND_HOLE429'(!)        = ''       | ''        | 'GND_HOLE429'           |'GND_C10OBD4-4X4-8B10'| 'IO'  | 'GND_C10OBD4-4X4-8B10'                            | ''             | ''          | ''           
 'TH'      | 'EMPTY'  | 'GND_HOLE343'(!)        = ''       | ''        | 'GND_HOLE343'           |'GND_C10D4-4B10'| 'IO'  | 'GND_C10D4-4B10'                                  | ''             | ''          | ''           
 'TH'      | 'EMPTY'  | 'GND_HOLE438'(!)        = ''       | ''        | 'GND_HOLE438'           |'GND_C10-16D4B10-16_OB3-81XC5-08B'| 'IO'  | 'GND_C10-16D4B10-16_OB3-81XC5-08B'                | ''             | ''          | ''           
 'TH'      | 'EMPTY'  | 'SP_GND_HOLE438'(!)     = ''       | ''        | 'GND_HOLE438'           |'G_GND_C10-16D4B10-16_OB3-81XC5-08B'| 'IO'  | 'G_GND_C10-16D4B10-16_OB3-81XC5-08B_FOR SEL'      | ''             | ''          | ''           
 'TH'      | 'EMPTY'  | 'GND_HOLE431'(!)        = ''       | ''        | 'GND_HOLE431'           |'GND_C8D3-3B8'| 'IO'  | 'GND_C8D3-3B8'                                    | ''             | ''          | ''           
 'TH'      | 'EMPTY'  | 'GND_HOLE313'(!)        = ''       | ''        | 'GND_HOLE313'           |'GND_C10D4B10_OB7XC5B'| 'IO'  | 'GND_C10D4B10_OB7XC5B'                            | ''             | ''          | ''           
 'TH'      | 'EMPTY'  | 'GND_HOLE439'(!)        = ''       | ''        | 'GND_HOLE439'           |'GND_C10D7B10'| 'IO'  | 'GND_C10D7B10'                                    | ''             | ''          | ''           
 'TH'      | 'EMPTY'  | 'GND_HOLE442'(!)        = ''       | ''        | 'GND_HOLE442'           |'G_GND_C9D5-28B9'| 'IO'  | 'GND_C9D5-28B9 (FOR SEL)'                         | ''             | ''          | ''           
 'TH'      | 'EMPTY'  | 'GND_HOLE453'(!)        = ''       | ''        | 'GND_HOLE453'           |'GND_C10D4B10_OB3-5XC5B'| 'IO'  | 'GND_C10D4B10_OB3-5XC5B'                          | ''             | ''          | ''           
 'TH'      | 'EMPTY'  | 'GND_HOLE455'(!)        = ''       | ''        | 'GND_HOLE455'           |'GND_C8D3-2B12'| 'IO'  | 'GND_C8D3-2B12'                                   | ''             | ''          | ''           
 'TH'      | 'EMPTY'  | 'GND_HOLE456'(!)        = ''       | ''        | 'GND_HOLE456'           |'GND_C8OBD4X5-5_OB1-5XC4T'| 'IO'  | 'GND_C8OBD4X5-5_OB1-5XC4T'                        | ''             | ''          | ''           
 'TH'      | 'EMPTY'  | 'GND_HOLE457'(!)        = ''       | ''        | 'GND_HOLE457'           |'GND_C8D4T'| 'IO'  | 'GND_C8D4T'                                       | ''             | ''          | ''           
 'TH'      | 'EMPTY'  | 'GND_HOLE354'(!)        = ''       | ''        | 'GND_HOLE354'           |'GND_C9D3-6B9_OB4XC4-5B'| 'IO'  | 'GND_C9D3-6B9_OB4XC4-5B'                          | ''             | ''          | ''           
 'TH'      | 'EMPTY'  | 'GND_HOLE464'(!)        = ''       | ''        | 'GND_HOLE464'           |'GND_C10D3-2B_RB'| 'IO'  | 'GND_C10D3-2B_RB'                                 | ''             | ''          | ''           
 'TH'      | 'EMPTY'  | 'GND_HOLE468'(!)        = ''       | ''        | 'GND_HOLE468'           |'GND_C10D3-8B10_OB4-5XC5B'| 'IO'  | 'GND_C10D3-8B10_OB4-5XC5B'                        | ''             | ''          | ''           
 'TH'      | 'EMPTY'  | 'GND_HOLE469'(!)        = ''       | ''        | 'GND_HOLE469'           |'GND_C9D3-5T'| 'IO'  | 'GND_C9D3-5T'                                     | ''             | ''          | ''           
 'TH'      | 'EMPTY'  | 'GND_HOLE470'(!)        = ''       | ''        | 'GND_HOLE470'           |'GND_C10D3-3B8_OB3-5XC4B'| 'IO'  | 'GND_C10D3-3B8_OB3-5XC4B'                         | ''             | ''          | ''           
 'TH'      | 'EMPTY'  | 'GND_HOLE474'(!)        = ''       | ''        | 'GND_HOLE474'           |'GND_C10OBD5-7X6-7B10'| 'IO'  | 'GND_C10OBD5-7X6-7B10'                            | ''             | ''          | ''           
 'TH'      | 'EMPTY'  | 'GND_HOLE475'(!)        = ''       | ''        | 'GND_HOLE475'           |'GND_OB10X10-4OBD5-7X6-1B10X10-4'| 'IO'  | 'GND_OB10X10-4OBD5-7X6-1B10X10-4'                 | ''             | ''          | ''           
 'TH'      | 'EMPTY'  | 'GND_HOLE477'(!)        = ''       | ''        | 'GND_HOLE477'           |'GND_C10D5-7B9'| 'IO'  | 'GND_C10D5-7B9'                                   | ''             | ''          | ''           
 'TH'      | 'EMPTY'  | 'GND_HOLE478'(!)        = ''       | ''        | 'GND_HOLE478'           |'GND_C9D4-3B11_OB6XC4-5T_RB'| 'IO'  | 'GND_C9D4-3B11_OB6XC4-5T_RB'                      | ''             | ''          | ''           
 'TH'      | 'EMPTY'  | 'GND_HOLE479'(!)        = ''       | ''        | 'GND_HOLE479'           |'GND_C9D3-3B6_OB6XC3B'| 'IO'  | 'GND_C9D3-3B6_OB6XC3B'                            | ''             | ''          | ''           
 'TH'      | 'EMPTY'  | 'GND_HOLE486'(!)        = ''       | ''        | 'GND_HOLE486'           |'GND_C10D3-7B10'| 'IO'  | 'GND_C10D3-7B10'                                  | ''             | ''          | ''           
 'TH'      | 'EMPTY'  | 'GND_HOLE148'(!)        = ''       | ''        | 'GND_HOLE148'           |'GND_C10D4-4'| 'IO'  | 'GND_C10D4-4'                                     | ''             | ''          | ''           
 'TH'      | 'EMPTY'  | 'GND_HOLE233'(!)        = ''       | ''        | 'GND_HOLE233'           |'GND_C10-16D4-7B10-16'| 'IO'  | 'GNDHOLE_8PIN_C10-16D4-7B10-16'                   | ''             | ''          | ''           
 'TH'      | 'EMPTY'  | 'GND_HOLE489'(!)        = ''       | ''        | 'GND_HOLE489'           |'GND_C10D3-8B10_OB7XC5B'| 'IO'  | 'GND_C10D3-8B10_OB7XC5B'                          | ''             | ''          | ''           
 'TH'      | 'EMPTY'  | 'GND_HOLE490'(!)        = ''       | ''        | 'GND_HOLE490'           |'GND_C9D3-3B9'| 'IO'  | 'GND_C9D3-3B9'                                    | ''             | ''          | ''           
 'TH'      | 'EMPTY'  | 'GND_HOLE452'(!)        = ''       | ''        | 'GND_HOLE452'           |'GND_C6D2-7B6'| 'IO'  | 'GND_C6D2-7B6'                                    | ''             | ''          | ''           
 'TH'      | 'EMPTY'  | 'GND_HOLE493'(!)        = ''       | ''        | 'GND_HOLE493'           |'GND_C10D4B10_OB3-5XC5'| 'IO'  | 'GND_C10D4B10_OB3-5XC5'                           | ''             | ''          | ''           
 'TH'      | 'EMPTY'  | 'GND_HOLE494'(!)        = ''       | ''        | 'GND_HOLE494'           |'GND_C10D3-7B10_RB'| 'IO'  | 'GND_C10D3-7B10_RB'                               | ''             | ''          | ''           
 'TH'      | 'EMPTY'  | 'GND_HOLE497'(!)        = ''       | ''        | 'GND_HOLE497'           |'GND_C9D4B9_OB3-7XC4-5B'| 'IO'  | 'GND_C9D4B9_OB3-7XC4-5B'                          | ''             | ''          | ''           
 'TH'      | 'EMPTY'  | 'GND_HOLE498'(!)        = ''       | ''        | 'GND_HOLE498'           |'GND_C5D2-4T'| 'IO'  | 'GND_C5D2-4T'                                     | ''             | ''          | ''           
 'TH'      | 'EMPTY'  | 'GND_HOLE499'(!)        = ''       | ''        | 'GND_HOLE499'           |'GND_C10D3-18B10_RB'| 'IO'  | 'GND_C10D3-18B10_RB'                              | ''             | ''          | ''           
 'TH'      | 'EMPTY'  | 'GND_HOLE173'(!)        = ''       | ''        | 'GND_HOLE173'           |'GND_C10D4-2B10'| 'IO'  | 'GNDHOLE_8PIN_C10D4-2B10'                         | ''             | ''          | ''           
 'TH'      | 'EMPTY'  | 'GND_HOLE368'(!)        = ''       | ''        | 'GND_HOLE368'           |'GND_C10D4B10_OB6XC5'| 'IO'  | 'GND_C10D4B10_OB6XC5'                             | ''             | ''          | ''           
 'TH'      | 'EMPTY'  | 'GND_HOLE443'(!)        = ''       | ''        | 'GND_HOLE443'           |'GND_C8D5-6B8_OB3-5XC4T_RB'| 'IO'  | 'GND_C8D5-6B8_OB3-5XC4T_RB'                       | ''             | ''          | ''           
 'TH'      | 'EMPTY'  | 'GND_HOLE32'(!)         = ''       | ''        | 'GND_HOLE32'            |'GND_C10D3-3B10'| 'IO'  | 'GND_C10D3-3B10'                                  | ''             | ''          | ''           
 'TH'      | 'EMPTY'  | 'GND_HOLE226'(!)        = ''       | ''        | 'GND_HOLE226'           |'GND_C7D3-18B7'| 'IO'  | 'GND_C7D3-18B7'                                   | ''             | ''          | ''           
 'TH'      | 'EMPTY'  | 'GND_HOLE501'(!)        = ''       | ''        | 'GND_HOLE501'           |'GND_C10-25D3-7B9_OB12X4-5B'| 'IO'  | 'GND_C10-25D3-7B9_OB12X4-5B'                      | ''             | ''          | ''           
 'TH'      | 'EMPTY'  | 'GND_HOLE502'(!)        = ''       | ''        | 'GND_HOLE502'           |'GND_C7D2B_RB'| 'IO'  | 'GND_C7D2B_RB'                                    | ''             | ''          | ''           
 'TH'      | 'EMPTY'  | 'GND_HOLE106'(!)        = ''       | ''        | 'GND_HOLE106'           |'GND_C10D4'| 'IO'  | 'GND_C10D4'                                       | ''             | ''          | ''           
 'TH'      | 'EMPTY'  | 'GND_HOLE435'(!)        = ''       | ''        | 'GND_HOLE435'           |'GND_C10-26D4-06B10-26'| 'IO'  | 'GND_C10-26D4-06B10-26'                           | ''             | ''          | ''           
 'TH'      | 'EMPTY'  | 'GND_HOLE503'(!)        = ''       | ''        | 'GND_HOLE503'           |'GND_C5-5D3-2B7'| 'IO'  | 'GND_C5-5D3-2B7'                                  | ''             | ''          | ''           
 'TH'      | 'EMPTY'  | 'GND_HOLE505'(!)        = ''       | ''        | 'GND_HOLE505'           |'GND_C10OBD4-8X5-2B10'| 'IO'  | 'GND_C10OBD4-8X5-2B10'                            | ''             | ''          | ''           
 'TH'      | 'EMPTY'  | 'GND_HOLE506'(!)        = ''       | ''        | 'GND_HOLE506'           |'GND_OB10X10-4OBD4-8X5-2B10X10-4_RB'| 'IO'  | 'GND_OB10X10-4OBD4-8X5-2B10X10-4_RB'              | ''             | ''          | ''           
 'TH'      | 'EMPTY'  | 'GND_HOLE507'(!)        = ''       | ''        | 'GND_HOLE507'           |'GND_C11D3-2B11_RB'| 'IO'  | 'GND_C11D3-2B11_RB'                               | ''             | ''          | ''           
 'TH'      | 'EMPTY'  | 'GND_HOLE508'(!)        = ''       | ''        | 'GND_HOLE508'           |'GND_C8D3-175B8_RB'| 'IO'  | 'GND_C8D3-175B8_RB'                               | ''             | ''          | ''           
 'TH'      | 'EMPTY'  | 'GND_HOLE509'(!)        = ''       | ''        | 'GND_HOLE509'           |'GND_C8D4-9B8_RB'| 'IO'  | 'GND_C8D4-9B8_RB'                                 | ''             | ''          | ''           
 'TH'      | 'EMPTY'  | 'GND_HOLE437'(!)        = ''       | ''        | 'GND_HOLE437'           |'GND_C10D6-4B10_OB10-5XC5B'| 'IO'  | 'GND_C10D6-4B10_OB10-5XC5B'                       | ''             | ''          | ''           
 'TH'      | 'EMPTY'  | 'GND_HOLE511'(!)        = ''       | ''        | 'GND_HOLE511'           |'GND_C9D4B9_OB4-5XC4-5B'| 'IO'  | 'GND_C9D4B9_OB4-5XC4-5B'                          | ''             | ''          | ''           
 'TH'      | 'EMPTY'  | 'GND_HOLE512'(!)        = ''       | ''        | 'GND_HOLE512'           |'G_GND_C12-7D3-58B_OB10-92XC6-35_IY2-03'| 'IO'  | 'G_GND_C12-7D3-58B_OB10-92XC6-35_IY2-03'          | ''             | ''          | ''           
 'TH'      | 'EMPTY'  | 'GND_HOLE513'(!)        = ''       | ''        | 'GND_HOLE513'           |'G_GND_OB12-7X23-62OBD3-58X5-08B_IY2-03'| 'IO'  | 'G_GND_OB12-7X23-62OBD3-58X5-08B_IY2-03'          | ''             | ''          | ''           
 'TH'      | 'EMPTY'  | 'GND_HOLE514'(!)        = ''       | ''        | 'GND_HOLE514'           |'GND_C10D6-5B10_NPM_RB_NSP'| 'IO'  | 'GND_C10D6-5B10_NPM_RB_NSP'                       | ''             | ''          | ''           
 'TH'      | 'EMPTY'  | 'GND_HOLE280'(!)        = ''       | ''        | 'GND_HOLE280'           |'GND_BOT10-16D3-96_O7-62XC10-16B'| 'IO'  | 'GND_BOT10-16D3-96_O7-62xC10-16B'                 | ''             | ''          | ''           
 'TH'      | 'EMPTY'  | 'GND_HOLE472'(!)        = ''       | ''        | 'GND_HOLE472'           |'GND_C10D3-3B10_OB5XC5B'| 'IO'  | 'GND_C10D3-3B10_OB5XC5B'                          | ''             | ''          | ''           
 'TH'      | 'EMPTY'  | 'GND_HOLE136'(!)        = ''       | ''        | 'GND_HOLE136'           |'G-GND_C8D4'| 'IO'  | 'G-GND_C8D4'                                      | ''             | ''          | ''           
 'TH'      | 'EMPTY'  | 'GND_HOLE515'(!)        = ''       | ''        | 'GND_HOLE515'           |'GND_C5D2-5B_RB'| 'IO'  | 'GND_C5D2-5B_RB'                                  | ''             | ''          | ''           
 'TH'      | 'EMPTY'  | 'GND_HOLE516'(!)        = ''       | ''        | 'GND_HOLE516'           |'GND_C9-5D6-5B9-5'| 'IO'  | 'GND_C9-5D6-5B9-5'                                | ''             | ''          | ''           
 'TH'      | 'EMPTY'  | 'GND_HOLE467'(!)        = ''       | ''        | 'GND_HOLE467'           |'GND_C9D6-4B9_T0-08_-0_M_PLT13-5_NUT'| 'IO'  | 'GND_C9D6-4B9_T0-08_-0_M_PLT13-5_NUT'             | ''             | ''          | ''           
 'TH'      | 'EMPTY'  | 'SP_GND_HOLE467'(!)     = ''       | ''        | 'GND_HOLE467'           |'G_GND_C9D6-4B9_T0-08_-0_M_PLT13-5_NUT'| 'IO'  | 'G_GND_C9D6-4B9_T0-08_-0_M_PLT13-5_NUT (FOR SEL)' | ''             | ''          | ''           
 'TH'      | 'EMPTY'  | 'GND_HOLE517'(!)        = ''       | ''        | 'GND_HOLE517'           |'GND_C9D6-4B9'| 'IO'  | 'GND_C9D6-4B9'                                    | ''             | ''          | ''           
 'TH'      | 'EMPTY'  | 'SP_GND_HOLE517'(!)     = ''       | ''        | 'GND_HOLE517'           |'G_GND_C9D6-4B9'| 'IO'  | 'G_GND_C9D6-4B9'                                  | ''             | ''          | ''           
 'TH'      | 'EMPTY'  | 'GND_HOLE487'(!)        = ''       | ''        | 'GND_HOLE487'           |'GND_C7-3D3-4B7-3'| 'IO'  | 'GND_C7-3D3-4B7-3'                                | ''             | ''          | ''           
 'TH'      | 'EMPTY'  | 'GND_HOLE34'(!)         = ''       | ''        | 'GND_HOLE34'            |'GND_C8D5-2B8'| 'IO'  | 'GND_C8D5-2B8'                                    | ''             | ''          | ''           
 'TH'      | 'EMPTY'  | 'GND_HOLE331'(!)        = ''       | ''        | 'GND_HOLE331'           |'GND_C8D4-2B10_OB7XC5B'| 'IO'  | 'GND_C8D4-2B10_OB7XC5B'                           | ''             | ''          | ''           
 'TH'      | 'EMPTY'  | 'GND_HOLE31'(!)         = ''       | ''        | 'GND_HOLE31'            |'GND_C10D5-2B10'| 'IO'  | 'GND_C10D5-2B10'                                  | ''             | ''          | ''           
 'TH'      | 'EMPTY'  | 'GND_HOLE521'(!)        = ''       | ''        | 'GND_HOLE521'           |'GND_C10OBD5-2X5-7B10'| 'IO'  | 'GND_C10OBD5-2X5-7B10'                            | ''             | ''          | ''           
 'TH'      | 'EMPTY'  | 'SP_GND_HOLE226'(!)     = ''       | ''        | 'GND_HOLE226'           |'G_GND_C7D3-18B7'| 'IO'  | 'GNDHOLE_8PIN_C7D3-18B7'                          | ''             | ''          | ''           
 'TH'      | 'EMPTY'  | 'GND_HOLE12'(!)         = ''       | ''        | 'GND_HOLE12'            |'GND_C8D4B8'| 'IO'  | 'GND_C8D4B8'                                      | ''             | ''          | ''           
 'TH'      | 'EMPTY'  | 'GND_HOLE473'(!)        = ''       | ''        | 'GND_HOLE473'           |'GND_C10D3-3B10_OB8XC5B'| 'IO'  | 'GND_C10D3-3B10_OB8XC5B'                          | ''             | ''          | ''           
 'TH'      | 'EMPTY'  | 'GND_HOLE109'(!)        = ''       | ''        | 'GND_HOLE109'           |'GND_C9D3-4B9'| 'IO'  | 'GNDHOLE_8PIN_C9D3-4B9'                           | ''             | ''          | ''           
 'TH'      | 'EMPTY'  | 'GND_HOLE522'(!)        = ''       | ''        | 'GND_HOLE522'           |'GND_OB10X10-7OBD4-5X5-2B10X10-7'| 'IO'  | 'GND_OB10X10-7OBD4-5X5-2B10X10-7'                 | ''             | ''          | ''           
 'TH'      | 'EMPTY'  | 'GND_HOLE523'(!)        = ''       | ''        | 'GND_HOLE523'           |'GND_C10D3-7B10_OB22XC5T_RB'| 'IO'  | 'GND_C10D3-7B10_OB22XC5T_RB'                      | ''             | ''          | ''           
 'TH'      | 'EMPTY'  | 'SP_GND_HOLE523'(!)     = ''       | ''        | 'GND_HOLE523'           |'G_GND_C10D3-7B10_OB22XC5T_RB'| 'IO'  | 'G_GND_C10D3-7B10_OB22XC5T_RB (FOR SEL)'          | ''             | ''          | ''           
 'TH'      | 'EMPTY'  | 'GND_HOLE524'(!)        = ''       | ''        | 'GND_HOLE524'           |'GND_C10D4B10_OB22XC5T_RB'| 'IO'  | 'GND_C10D4B10_OB22XC5T_RB'                        | ''             | ''          | ''           
 'TH'      | 'EMPTY'  | 'SP_GND_HOLE524'(!)     = ''       | ''        | 'GND_HOLE524'           |'G_GND_C10D4B10_OB22XC5T_RB'| 'IO'  | 'G_GND_C10D4B10_OB22XC5T_RB (FOR SEL)'            | ''             | ''          | ''           
 'TH'      | 'EMPTY'  | 'GND_HOLE254'(!)        = ''       | ''        | 'GND_HOLE254'           |'GND_C6D3B6'| 'IO'  | 'GND_C6D3B6'                                      | ''             | ''          | ''           
 'TH'      | 'EMPTY'  | 'SP_GND_HOLE254'(!)     = ''       | ''        | 'GND_HOLE254'           |'G_GND_C6D3B6'| 'IO'  | 'G_GND_C6D3B6 (FOR SEL)'                          | ''             | ''          | ''           
 'TH'      | 'EMPTY'  | 'GND_HOLE525'(!)        = ''       | ''        | 'GND_HOLE525'           |'GND_C8-5D4-5B8-5'| 'IO'  | 'GND_C8-5D4-5B8-5'                                | ''             | ''          | ''           
 'TH'      | 'EMPTY'  | 'GND_HOLE526'(!)        = ''       | ''        | 'GND_HOLE526'           |'GND_C8-5D3-7B8-5'| 'IO'  | 'GND_C8-5D3-7B8-5'                                | ''             | ''          | ''           
 'TH'      | 'EMPTY'  | 'GND_HOLE527'(!)        = ''       | ''        | 'GND_HOLE527'           |'GND_C10D4-5B10_OB5XC5B'| 'IO'  | 'GND_C10D4-5B10_OB5XC5B'                          | ''             | ''          | ''           
 'TH'      | 'EMPTY'  | 'SP_GND_HOLE527'(!)     = ''       | ''        | 'GND_HOLE527'           |'G_GND_C10D4-5B10_OB5XC5B'| 'IO'  | 'G_GND_C10D4-5B10_OB5XC5B (FOR SEL)'              | ''             | ''          | ''           
 'TH'      | 'EMPTY'  | 'GND_HOLE528'(!)        = ''       | ''        | 'GND_HOLE528'           |'GND_S12D3-7B10_IX-2T'| 'IO'  | 'GND_S12D3-7B10_IX-2T'                            | ''             | ''          | ''           
 'TH'      | 'EMPTY'  | 'SP_GND_HOLE528'(!)     = ''       | ''        | 'GND_HOLE528'           |'G_GND_S12D3-7B10_IX-2T'| 'IO'  | 'G_GND_S12D3-7B10_IX-2T (FOR SEL)'                | ''             | ''          | ''           
 'TH'      | 'EMPTY'  | 'GND_HOLE529'(!)        = ''       | ''        | 'GND_HOLE529'           |'GND_C10OBD4-5X5B10_OB5XC5B'| 'IO'  | 'GND_C10OBD4-5X5B10_OB5XC5B'                      | ''             | ''          | ''           
 'TH'      | 'EMPTY'  | 'SP_GND_HOLE529'(!)     = ''       | ''        | 'GND_HOLE529'           |'G_GND_C10OBD4-5X5B10_OB5XC5B'| 'IO'  | 'G_GND_C10OBD4-5X5B10_OB5XC5B (FOR SEL)'          | ''             | ''          | ''           
 'TH'      | 'EMPTY'  | 'GND_HOLE530'(!)        = ''       | ''        | 'GND_HOLE530'           |'GND_C10D3-7B10_OB5XC5B'| 'IO'  | 'GND_C10D3-7B10_OB5XC5B'                          | ''             | ''          | ''           
 'TH'      | 'EMPTY'  | 'SP_GND_HOLE530'(!)     = ''       | ''        | 'GND_HOLE530'           |'G_GND_C10D3-7B10_OB5XC5B'| 'IO'  | 'G_GND_C10D3-7B10_OB5XC5B (FOR SEL)'              | ''             | ''          | ''           
 'TH'      | 'EMPTY'  | 'GND_HOLE531'(!)        = ''       | ''        | 'GND_HOLE531'           |'GND_C5-5D2-9B5-5'| 'IO'  | 'GND_C5-5D2-9B5-5'                                | ''             | ''          | ''           
 'TH'      | 'EMPTY'  | 'GND_HOLE415'(!)        = ''       | ''        | 'GND_HOLE415'           |'GND_C10D4B10_OB22XC5B'| 'IO'  | 'GND_C10D4B10_OB22XC5B'                           | ''             | ''          | ''           
 'TH'      | 'EMPTY'  | 'GND_HOLE447'(!)        = ''       | ''        | 'GND_HOLE447'           |'GND_C10D3-5B10-5_OB15XC5-25B'| 'IO'  | 'GND_C10D3-5B10-5_OB15XC5-25B'                    | ''             | ''          | ''           
 'TH'      | 'EMPTY'  | 'GND_HOLE131'(!)        = ''       | ''        | 'GND_HOLE131'           |'GND_C16D4B16'| 'IO'  | 'GNDHOLE_8PIN_C16D4B16'                           | ''             | ''          | ''           
 'TH'      | 'EMPTY'  | 'GND_HOLE532'(!)        = ''       | ''        | 'GND_HOLE532'           |'GND_C8D2-9B8'| 'IO'  | 'GND_C8D2-9B8'                                    | ''             | ''          | ''           
 'TH'      | 'EMPTY'  | 'GND_HOLE533'(!)        = ''       | ''        | 'GND_HOLE533'           |'GND_C6D3-4B6'| 'IO'  | 'GND_C6D3-4B6'                                    | ''             | ''          | ''           

END_PART

END.

